# S9S_MB_2U (Grand Teton) — schematic netlist excerpt (pin names and nets, part order shuffled) for the footprints in the layout excerpt that follows; sources: Cadence DE-HDL packaged netlist, KiCad conversion of 03242023_DA0F0TMBIJ0_F0T_Motherboard_J_brd_V01_OCP.brd

PR89  Q_RES  16.9K 1% CHIP  pkg 0402LF  page 258 : A = P5V_AUX_CS ; B = GND
R4213  Q_RES  0 5% CHIP  pkg 0402LF  page 170 : A = FM_THERMAL_ALERT_N ; B = FM_LM75_2_ALERT_N

(kicad_pcb
	(version 20260206)
	(generator "pcbnew")
	(generator_version "10.0")
	(general
		(thickness 1.6)
		(legacy_teardrops no)
	)
	(paper "A4")
	(title_block
		(title "03242023_DA0F0TMBIJ0_F0T_Motherboard_J_brd_V01_OCP.brd")
		(comment 1 "Grand Teton / footprints 1041-1042 of 6105")
	)
	(layers
		(0 "F.Cu" signal "TOP")
		(4 "In1.Cu" signal "GND")
		(6 "In2.Cu" signal "IN1")
		(8 "In3.Cu" signal "GND1")
		(10 "In4.Cu" signal "IN2")
		(12 "In5.Cu" signal "GND2")
		(14 "In6.Cu" signal "IN3")
		(16 "In7.Cu" signal "GND3")
		(18 "In8.Cu" signal "VCC")
		(20 "In9.Cu" signal "VCC1")
		(22 "In10.Cu" signal "GND4")
		(24 "In11.Cu" signal "IN4")
		(26 "In12.Cu" signal "GND5")
		(28 "In13.Cu" signal "IN5")
		(30 "In14.Cu" signal "GND6")
		(32 "In15.Cu" signal "IN6")
		(34 "In16.Cu" signal "GND7")
		(2 "B.Cu" signal "BOTTOM")
		(9 "F.Adhes" user "F.Adhesive")
		(11 "B.Adhes" user "B.Adhesive")
		(13 "F.Paste" user "Package Geometry/Pastemask Top")
		(15 "B.Paste" user "Package Geometry/Pastemask Bottom")
		(5 "F.SilkS" user "Ref Des/Silkscreen Top")
		(7 "B.SilkS" user "Ref Des/Silkscreen Bottom")
		(1 "F.Mask" user "Board Geometry/Soldermask Top")
		(3 "B.Mask" user "Board Geometry/Soldermask Bottom")
		(17 "Dwgs.User" user "User.Drawings")
		(19 "Cmts.User" user "User.Comments")
		(21 "Eco1.User" user "User.Eco1")
		(23 "Eco2.User" user "User.Eco2")
		(25 "Edge.Cuts" user "Board Geometry/Outline")
		(27 "Margin" user)
		(31 "F.CrtYd" user "Package Geometry/Place Bound Top")
		(29 "B.CrtYd" user "Package Geometry/Place Bound Bottom")
		(35 "F.Fab" user "Ref Des/Assembly Top")
		(33 "B.Fab" user "Ref Des/Assembly Bottom")
	)
	(footprint ""
		(layer "F.Cu")
		(at 456.621388 -381.264922 -90)
		(property "Reference" "PR89"
			(at 0 0 270)
			(layer "F.SilkS")
			(hide yes)
			(effects
				(font
					(size 1.27 1.27)
				)
			)
		)
		(property "Value" ""
			(at 0 0 270)
			(layer "F.Fab")
			(effects
				(font
					(size 1.27 1.27)
				)
			)
		)
		(duplicate_pad_numbers_are_jumpers no)
		(fp_line
			(start -0.7874 0.4064)
			(end -0.7874 -0.4064)
			(stroke
				(width 0.1524)
				(type default)
			)
			(layer "F.SilkS")
		)
		(fp_line
			(start 0.7874 0.4064)
			(end -0.7874 0.4064)
			(stroke
				(width 0.1524)
				(type default)
			)
			(layer "F.SilkS")
		)
		(fp_line
			(start -0.7874 -0.4064)
			(end 0.7874 -0.4064)
			(stroke
				(width 0.1524)
				(type default)
			)
			(layer "F.SilkS")
		)
		(fp_line
			(start 0.7874 -0.4064)
			(end 0.7874 0.4064)
			(stroke
				(width 0.1524)
				(type default)
			)
			(layer "F.SilkS")
		)
		(fp_line
			(start -0.67945 0.3048)
			(end -0.67945 -0.305054)
			(stroke
				(width 0.1)
				(type default)
			)
			(layer "F.Fab")
		)
		(fp_line
			(start -0.12065 0.3048)
			(end -0.67945 0.3048)
			(stroke
				(width 0.1)
				(type default)
			)
			(layer "F.Fab")
		)
		(fp_line
			(start 0.120396 0.3048)
			(end 0.120396 0.2794)
			(stroke
				(width 0.1)
				(type default)
			)
			(layer "F.Fab")
		)
		(fp_line
			(start 0.67945 0.3048)
			(end 0.120396 0.3048)
			(stroke
				(width 0.1)
				(type default)
			)
			(layer "F.Fab")
		)
		(fp_line
			(start -0.12065 0.2794)
			(end -0.12065 0.3048)
			(stroke
				(width 0.1)
				(type default)
			)
			(layer "F.Fab")
		)
		(fp_line
			(start 0.120396 0.2794)
			(end -0.12065 0.2794)
			(stroke
				(width 0.1)
				(type default)
			)
			(layer "F.Fab")
		)
		(fp_line
			(start -0.12065 -0.2794)
			(end 0.12065 -0.2794)
			(stroke
				(width 0.1)
				(type default)
			)
			(layer "F.Fab")
		)
		(fp_line
			(start 0.12065 -0.2794)
			(end 0.12065 -0.3048)
			(stroke
				(width 0.1)
				(type default)
			)
			(layer "F.Fab")
		)
		(fp_line
			(start 0.12065 -0.3048)
			(end 0.67945 -0.3048)
			(stroke
				(width 0.1)
				(type default)
			)
			(layer "F.Fab")
		)
		(fp_line
			(start 0.67945 -0.3048)
			(end 0.67945 0.3048)
			(stroke
				(width 0.1)
				(type default)
			)
			(layer "F.Fab")
		)
		(fp_line
			(start -0.67945 -0.305054)
			(end -0.12065 -0.305054)
			(stroke
				(width 0.1)
				(type default)
			)
			(layer "F.Fab")
		)
		(fp_line
			(start -0.12065 -0.305054)
			(end -0.12065 -0.2794)
			(stroke
				(width 0.1)
				(type default)
			)
			(layer "F.Fab")
		)
		(pad "1" smd circle
			(at -0.40005 0 270)
			(size 0 0)
			(layers "F.Cu" "F.Mask" "F.Paste")
			(net "P5V_AUX_CS")
		)
		(pad "2" smd circle
			(at 0.40005 0 270)
			(size 0 0)
			(layers "F.Cu" "F.Mask" "F.Paste")
			(net "GND")
		)
	)
	(footprint ""
		(layer "F.Cu")
		(at 105.21188 -425.795948 180)
		(property "Reference" "R4213"
			(at 0 0 180)
			(layer "F.SilkS")
			(hide yes)
			(effects
				(font
					(size 1.27 1.27)
				)
			)
		)
		(property "Value" ""
			(at 0 0 180)
			(layer "F.Fab")
			(effects
				(font
					(size 1.27 1.27)
				)
			)
		)
		(duplicate_pad_numbers_are_jumpers no)
		(fp_line
			(start 0.7874 0.4064)
			(end -0.7874 0.4064)
			(stroke
				(width 0.1524)
				(type default)
			)
			(layer "F.SilkS")
		)
		(fp_line
			(start 0.7874 -0.4064)
			(end 0.7874 0.4064)
			(stroke
				(width 0.1524)
				(type default)
			)
			(layer "F.SilkS")
		)
		(fp_line
			(start -0.7874 0.4064)
			(end -0.7874 -0.4064)
			(stroke
				(width 0.1524)
				(type default)
			)
			(layer "F.SilkS")
		)
		(fp_line
			(start -0.7874 -0.4064)
			(end 0.7874 -0.4064)
			(stroke
				(width 0.1524)
				(type default)
			)
			(layer "F.SilkS")
		)
		(fp_line
			(start 0.67945 0.3048)
			(end 0.120396 0.3048)
			(stroke
				(width 0.1)
				(type default)
			)
			(layer "F.Fab")
		)
		(fp_line
			(start 0.67945 -0.3048)
			(end 0.67945 0.3048)
			(stroke
				(width 0.1)
				(type default)
			)
			(layer "F.Fab")
		)
		(fp_line
			(start 0.12065 -0.2794)
			(end 0.12065 -0.3048)
			(stroke
				(width 0.1)
				(type default)
			)
			(layer "F.Fab")
		)
		(fp_line
			(start 0.12065 -0.3048)
			(end 0.67945 -0.3048)
			(stroke
				(width 0.1)
				(type default)
			)
			(layer "F.Fab")
		)
		(fp_line
			(start 0.120396 0.3048)
			(end 0.120396 0.2794)
			(stroke
				(width 0.1)
				(type default)
			)
			(layer "F.Fab")
		)
		(fp_line
			(start 0.120396 0.2794)
			(end -0.12065 0.2794)
			(stroke
				(width 0.1)
				(type default)
			)
			(layer "F.Fab")
		)
		(fp_line
			(start -0.12065 0.3048)
			(end -0.67945 0.3048)
			(stroke
				(width 0.1)
				(type default)
			)
			(layer "F.Fab")
		)
		(fp_line
			(start -0.12065 0.2794)
			(end -0.12065 0.3048)
			(stroke
				(width 0.1)
				(type default)
			)
			(layer "F.Fab")
		)
		(fp_line
			(start -0.12065 -0.2794)
			(end 0.12065 -0.2794)
			(stroke
				(width 0.1)
				(type default)
			)
			(layer "F.Fab")
		)
		(fp_line
			(start -0.12065 -0.305054)
			(end -0.12065 -0.2794)
			(stroke
				(width 0.1)
				(type default)
			)
			(layer "F.Fab")
		)
		(fp_line
			(start -0.67945 0.3048)
			(end -0.67945 -0.305054)
			(stroke
				(width 0.1)
				(type default)
			)
			(layer "F.Fab")
		)
		(fp_line
			(start -0.67945 -0.305054)
			(end -0.12065 -0.305054)
			(stroke
				(width 0.1)
				(type default)
			)
			(layer "F.Fab")
		)
		(pad "1" smd circle
			(at -0.40005 0 180)
			(size 0 0)
			(layers "F.Cu" "F.Mask" "F.Paste")
			(net "FM_THERMAL_ALERT_N")
		)
		(pad "2" smd circle
			(at 0.40005 0 180)
			(size 0 0)
			(layers "F.Cu" "F.Mask" "F.Paste")
			(net "FM_LM75_2_ALERT_N")
		)
	)
)
